(kicad_pcb
	(version 20260206)
	(generator "pcbnew")
	(generator_version "10.0")
	(general
		(thickness 1.6)
		(legacy_teardrops no)
	)
	(paper "A4")
	(title_block
		(title "Wiwynn_Tioga_Pass_MB.brd")
		(comment 1 "Tioga Pass / footprints 2276-2282 of 4770")
	)
	(layers
		(0 "F.Cu" signal "TOP")
		(4 "In1.Cu" signal "L2GND")
		(6 "In2.Cu" signal "L3")
		(8 "In3.Cu" signal "L4GND")
		(10 "In4.Cu" signal "L5")
		(12 "In5.Cu" signal "L6GND")
		(14 "In6.Cu" signal "L7VCC")
		(16 "In7.Cu" signal "L8VCC")
		(18 "In8.Cu" signal "L9GND")
		(20 "In9.Cu" signal "L10")
		(22 "In10.Cu" signal "L11GND")
		(24 "In11.Cu" signal "L12")
		(26 "In12.Cu" signal "L13GND")
		(2 "B.Cu" signal "BOTTOM")
		(9 "F.Adhes" user "F.Adhesive")
		(11 "B.Adhes" user "B.Adhesive")
		(13 "F.Paste" user "Package Geometry/Pastemask Top")
		(15 "B.Paste" user "Package Geometry/Pastemask Bottom")
		(5 "F.SilkS" user "Ref Des/Silkscreen Top")
		(7 "B.SilkS" user "Ref Des/Silkscreen Bottom")
		(1 "F.Mask" user "Board Geometry/Soldermask Top")
		(3 "B.Mask" user "Board Geometry/Soldermask Bottom")
		(17 "Dwgs.User" user "User.Drawings")
		(19 "Cmts.User" user "User.Comments")
		(21 "Eco1.User" user "User.Eco1")
		(23 "Eco2.User" user "User.Eco2")
		(25 "Edge.Cuts" user "Board Geometry/Outline")
		(27 "Margin" user)
		(31 "F.CrtYd" user "Package Geometry/Place Bound Top")
		(29 "B.CrtYd" user "Package Geometry/Place Bound Bottom")
		(35 "F.Fab" user "Ref Des/Assembly Top")
		(33 "B.Fab" user "Ref Des/Assembly Bottom")
	)
	(footprint ""
		(layer "F.Cu")
		(at 458.431392 -39.480998 90)
		(property "Reference" "R9F6"
			(at 0 0 90)
			(layer "F.SilkS")
			(hide yes)
			(effects
				(font
					(size 1.27 1.27)
				)
			)
		)
		(property "Value" "*"
			(at 0.064008 -4.108196 90)
			(unlocked yes)
			(layer "F.Fab")
			(hide yes)
			(effects
				(font
					(size 1.27 1.016)
					(thickness 0.1524)
				)
			)
		)
		(property "Device Type" "4K42R2F-GP_SMD-RG-4K42R2F-GP,6A"
			(at 0.064008 -5.632196 90)
			(unlocked yes)
			(layer "F.Fab")
			(hide yes)
			(effects
				(font
					(size 1.27 1.016)
					(thickness 0.1524)
				)
			)
		)
		(duplicate_pad_numbers_are_jumpers no)
		(fp_line
			(start 0.508 -0.9398)
			(end -0.508 -0.9398)
			(stroke
				(width 0.1524)
				(type default)
			)
			(layer "F.SilkS")
		)
		(fp_line
			(start -0.508 -0.9398)
			(end -0.508 0.9398)
			(stroke
				(width 0.1524)
				(type default)
			)
			(layer "F.SilkS")
		)
		(fp_rect
			(start -0.508 0.9398)
			(end 0.508 -0.9398)
			(stroke
				(width 0)
				(type default)
			)
			(fill no)
			(layer "F.CrtYd")
		)
		(fp_rect
			(start -0.508 0.9398)
			(end 0.508 -0.9398)
			(stroke
				(width 0)
				(type default)
			)
			(fill no)
			(layer "F.Fab")
		)
		(pad "1" smd custom
			(at 0 -0.4445 90)
			(size 0.1397 0.1397)
			(layers "F.Cu" "F.Mask" "F.Paste")
			(net "P1V15_AUX_BMC")
			(options
				(clearance outline)
				(anchor circle)
			)
			(primitives
				(gr_poly
					(pts
						(arc
							(start -0.1778 -0.2794)
							(mid -0.249642 -0.249642)
							(end -0.2794 -0.1778)
						)
						(arc
							(start -0.2794 0.1778)
							(mid -0.249642 0.249642)
							(end -0.1778 0.2794)
						)
						(arc
							(start 0.1778 0.2794)
							(mid 0.249642 0.249642)
							(end 0.2794 0.1778)
						)
						(arc
							(start 0.2794 -0.1778)
							(mid 0.249642 -0.249642)
							(end 0.1778 -0.2794)
						)
					)
					(width 0)
					(fill yes)
				)
			)
		)
		(pad "2" smd custom
			(at 0 0.4445 90)
			(size 0.1397 0.1397)
			(layers "F.Cu" "F.Mask" "F.Paste")
			(net "VR_P1V15_BMC_STBY_FB")
			(options
				(clearance outline)
				(anchor circle)
			)
			(primitives
				(gr_poly
					(pts
						(arc
							(start -0.1778 -0.2794)
							(mid -0.249642 -0.249642)
							(end -0.2794 -0.1778)
						)
						(arc
							(start -0.2794 0.1778)
							(mid -0.249642 0.249642)
							(end -0.1778 0.2794)
						)
						(arc
							(start 0.1778 0.2794)
							(mid 0.249642 0.249642)
							(end 0.2794 0.1778)
						)
						(arc
							(start 0.2794 -0.1778)
							(mid 0.249642 -0.249642)
							(end 0.1778 -0.2794)
						)
					)
					(width 0)
					(fill yes)
				)
			)
		)
	)
	(footprint ""
		(layer "F.Cu")
		(at 6.35 -126.111 90)
		(property "Reference" "C1B11"
			(at 0 0 90)
			(layer "F.SilkS")
			(hide yes)
			(effects
				(font
					(size 1.27 1.27)
				)
			)
		)
		(property "Value" ""
			(at 0 0 90)
			(layer "F.Fab")
			(effects
				(font
					(size 1.27 1.27)
				)
			)
		)
		(duplicate_pad_numbers_are_jumpers no)
		(fp_rect
			(start -0.3048 -0.1016)
			(end 0.3048 0.9906)
			(stroke
				(width 0)
				(type default)
			)
			(fill no)
			(layer "F.CrtYd")
		)
		(fp_line
			(start 0.3048 -0.1016)
			(end -0.3048 -0.1016)
			(stroke
				(width 0.1)
				(type default)
			)
			(layer "F.Fab")
		)
		(fp_line
			(start -0.3048 -0.1016)
			(end -0.3048 0.9906)
			(stroke
				(width 0.1)
				(type default)
			)
			(layer "F.Fab")
		)
		(fp_line
			(start 0.3048 0.9906)
			(end 0.3048 -0.1016)
			(stroke
				(width 0.1)
				(type default)
			)
			(layer "F.Fab")
		)
		(fp_line
			(start -0.3048 0.9906)
			(end 0.3048 0.9906)
			(stroke
				(width 0.1)
				(type default)
			)
			(layer "F.Fab")
		)
		(pad "1" smd rect
			(at 0 0 90)
			(size 0.508 0.508)
			(layers "F.Cu" "F.Mask" "F.Paste")
			(net "A_TSENSE_PVDDQ_KLM")
		)
		(pad "2" smd rect
			(at 0 0.889 90)
			(size 0.508 0.508)
			(layers "F.Cu" "F.Mask" "F.Paste")
			(net "GND")
		)
		(zone
			(layer "F.Cu")
			(hatch none 0.5)
			(connect_pads
				(clearance 0)
			)
			(min_thickness 0.25)
			(keepout
				(tracks allowed)
				(vias not_allowed)
				(pads allowed)
				(copperpour not_allowed)
				(footprints allowed)
			)
			(placement
				(enabled no)
				(sheetname "")
			)
			(fill
				(thermal_gap 0.5)
				(thermal_bridge_width 0.5)
				(island_removal_mode 0)
			)
			(polygon
				(pts
					(xy 6.604 -125.857) (xy 6.985 -125.857) (xy 6.985 -126.365) (xy 6.604 -126.365)
				)
			)
		)
		(zone
			(layer "F.Cu")
			(hatch none 0.5)
			(connect_pads
				(clearance 0)
			)
			(min_thickness 0.25)
			(keepout
				(tracks not_allowed)
				(vias allowed)
				(pads allowed)
				(copperpour not_allowed)
				(footprints allowed)
			)
			(placement
				(enabled no)
				(sheetname "")
			)
			(fill
				(thermal_gap 0.5)
				(thermal_bridge_width 0.5)
				(island_removal_mode 0)
			)
			(polygon
				(pts
					(xy 6.604 -125.857) (xy 6.985 -125.857) (xy 6.985 -126.365) (xy 6.604 -126.365)
				)
			)
		)
	)
	(footprint ""
		(layer "F.Cu")
		(at 447.4718 -129.5146 180)
		(property "Reference" "C9B1"
			(at 0 0 180)
			(layer "F.SilkS")
			(hide yes)
			(effects
				(font
					(size 1.27 1.27)
				)
			)
		)
		(property "Value" ""
			(at 0 0 180)
			(layer "F.Fab")
			(effects
				(font
					(size 1.27 1.27)
				)
			)
		)
		(duplicate_pad_numbers_are_jumpers no)
		(fp_poly
			(pts
				(xy -0.7239 -0.2159) (xy 0.7239 -0.2159) (xy 0.7239 1.9939) (xy -0.7239 1.9939)
			)
			(stroke
				(width 0)
				(type default)
			)
			(fill no)
			(layer "F.CrtYd")
		)
		(fp_line
			(start 0.7239 1.9939)
			(end 0.7239 -0.2159)
			(stroke
				(width 0.1)
				(type default)
			)
			(layer "F.Fab")
		)
		(fp_line
			(start 0.7239 -0.2159)
			(end -0.7239 -0.2159)
			(stroke
				(width 0.1)
				(type default)
			)
			(layer "F.Fab")
		)
		(fp_line
			(start -0.7239 1.9939)
			(end 0.7239 1.9939)
			(stroke
				(width 0.1)
				(type default)
			)
			(layer "F.Fab")
		)
		(fp_line
			(start -0.7239 -0.2159)
			(end -0.7239 1.9939)
			(stroke
				(width 0.1)
				(type default)
			)
			(layer "F.Fab")
		)
		(pad "1" smd rect
			(at 0 0 180)
			(size 1.27 1.016)
			(layers "F.Cu" "F.Mask" "F.Paste")
			(net "P5V_HDD_SATA")
		)
		(pad "2" smd rect
			(at 0 1.778 180)
			(size 1.27 1.016)
			(layers "F.Cu" "F.Mask" "F.Paste")
			(net "GND")
		)
		(zone
			(layer "F.Cu")
			(hatch none 0.5)
			(connect_pads
				(clearance 0)
			)
			(min_thickness 0.25)
			(keepout
				(tracks not_allowed)
				(vias allowed)
				(pads allowed)
				(copperpour not_allowed)
				(footprints allowed)
			)
			(placement
				(enabled no)
				(sheetname "")
			)
			(fill
				(thermal_gap 0.5)
				(thermal_bridge_width 0.5)
				(island_removal_mode 0)
			)
			(polygon
				(pts
					(xy 448.1068 -130.0226) (xy 446.8368 -130.0226) (xy 446.8368 -130.7846) (xy 448.1068 -130.7846)
				)
			)
		)
	)
	(footprint ""
		(layer "F.Cu")
		(at 5.923788 -3.00101 -90)
		(property "Reference" "CF19"
			(at 0 0 270)
			(layer "F.SilkS")
			(hide yes)
			(effects
				(font
					(size 1.27 1.27)
				)
			)
		)
		(property "Value" "*"
			(at 1.1811 -2.8194 270)
			(unlocked yes)
			(layer "F.Fab")
			(hide yes)
			(effects
				(font
					(size 1.27 1.016)
					(thickness 0.1524)
				)
			)
		)
		(property "Device Type" "SC22P50V2JN-4GP_SMD-BCG-SC22P5A"
			(at 1.1811 -4.3434 270)
			(unlocked yes)
			(layer "F.Fab")
			(hide yes)
			(effects
				(font
					(size 1.27 1.016)
					(thickness 0.1524)
				)
			)
		)
		(duplicate_pad_numbers_are_jumpers no)
		(fp_rect
			(start -0.4318 0.9525)
			(end 0.4318 -0.9525)
			(stroke
				(width 0)
				(type default)
			)
			(fill no)
			(layer "F.CrtYd")
		)
		(fp_rect
			(start -0.4318 0.9525)
			(end 0.4318 -0.9525)
			(stroke
				(width 0)
				(type default)
			)
			(fill no)
			(layer "F.Fab")
		)
		(pad "1" smd custom
			(at 0 -0.4445 270)
			(size 0.1524 0.1524)
			(layers "F.Cu" "F.Mask" "F.Paste")
			(net "VR_PVDDQ_GHJ_AIREF1")
			(options
				(clearance outline)
				(anchor circle)
			)
			(primitives
				(gr_poly
					(pts
						(arc
							(start 0.3048 -0.2032)
							(mid 0.275042 -0.275042)
							(end 0.2032 -0.3048)
						)
						(arc
							(start -0.2032 -0.3048)
							(mid -0.275042 -0.275042)
							(end -0.3048 -0.2032)
						)
						(arc
							(start -0.3048 0.2032)
							(mid -0.275042 0.275042)
							(end -0.2032 0.3048)
						)
						(arc
							(start 0.2032 0.3048)
							(mid 0.275042 0.275042)
							(end 0.3048 0.2032)
						)
					)
					(width 0)
					(fill yes)
				)
			)
		)
		(pad "2" smd custom
			(at 0 0.4445 270)
			(size 0.1524 0.1524)
			(layers "F.Cu" "F.Mask" "F.Paste")
			(net "ISENSE_PVDDQ_GHJ_PH1_IMON")
			(options
				(clearance outline)
				(anchor circle)
			)
			(primitives
				(gr_poly
					(pts
						(arc
							(start 0.3048 -0.2032)
							(mid 0.275042 -0.275042)
							(end 0.2032 -0.3048)
						)
						(arc
							(start -0.2032 -0.3048)
							(mid -0.275042 -0.275042)
							(end -0.3048 -0.2032)
						)
						(arc
							(start -0.3048 0.2032)
							(mid -0.275042 0.275042)
							(end -0.2032 0.3048)
						)
						(arc
							(start 0.2032 0.3048)
							(mid 0.275042 0.275042)
							(end 0.3048 0.2032)
						)
					)
					(width 0)
					(fill yes)
				)
			)
		)
	)
	(footprint ""
		(layer "F.Cu")
		(at 20.2946 -41.402 180)
		(property "Reference" "U1E2"
			(at 2.2606 2.25933 0)
			(unlocked yes)
			(layer "F.SilkS")
			(effects
				(font
					(size 0.7874 0.5842)
					(thickness 0.1524)
				)
				(justify left)
			)
		)
		(property "Value" ""
			(at 0 0 180)
			(layer "F.Fab")
			(effects
				(font
					(size 1.27 1.27)
				)
			)
		)
		(duplicate_pad_numbers_are_jumpers no)
		(fp_circle
			(center -1.2192 -0.35814)
			(end -1.3462 -0.35814)
			(stroke
				(width 0.254)
				(type default)
			)
			(fill no)
			(layer "F.SilkS")
		)
		(fp_poly
			(pts
				(xy 0.21463 -0.450088) (xy 1.56337 -0.450088) (xy 1.56337 1.75006) (xy 0.21463 1.75006)
			)
			(stroke
				(width 0)
				(type default)
			)
			(fill no)
			(layer "F.CrtYd")
		)
		(fp_line
			(start 1.56337 1.75006)
			(end 0.21463 1.75006)
			(stroke
				(width 0.1)
				(type default)
			)
			(layer "F.Fab")
		)
		(fp_line
			(start 1.56337 -0.450088)
			(end 1.56337 1.75006)
			(stroke
				(width 0.1)
				(type default)
			)
			(layer "F.Fab")
		)
		(fp_line
			(start 0.21463 1.75006)
			(end 0.21463 -0.450088)
			(stroke
				(width 0.1)
				(type default)
			)
			(layer "F.Fab")
		)
		(fp_line
			(start 0.21463 -0.450088)
			(end 1.56337 -0.450088)
			(stroke
				(width 0.1)
				(type default)
			)
			(layer "F.Fab")
		)
		(fp_circle
			(center -0.4699 -0.8382)
			(end -0.5969 -0.8382)
			(stroke
				(width 0.254)
				(type default)
			)
			(fill no)
			(layer "F.Fab")
		)
		(pad "1" smd rect
			(at 0 0 180)
			(size 1.016 0.381)
			(layers "F.Cu" "F.Mask" "F.Paste")
			(net "FM_CTNR_PS_ON")
		)
		(pad "2" smd rect
			(at 0 0.649986 180)
			(size 1.016 0.381)
			(layers "F.Cu" "F.Mask" "F.Paste")
			(net "FM_DISABLE_FAN_N")
		)
		(pad "3" smd rect
			(at 0 1.299972 180)
			(size 1.016 0.381)
			(layers "F.Cu" "F.Mask" "F.Paste")
			(net "GND")
		)
		(pad "4" smd rect
			(at 1.778 1.299972 180)
			(size 1.016 0.381)
			(layers "F.Cu" "F.Mask" "F.Paste")
			(net "FM_ENABLE_FAN_POWER")
		)
		(pad "5" smd rect
			(at 1.778 0 180)
			(size 1.016 0.381)
			(layers "F.Cu" "F.Mask" "F.Paste")
			(net "P3V3_STBY")
		)
	)
	(footprint ""
		(layer "F.Cu")
		(at 281.178 -73.152 90)
		(property "Reference" "R6D9"
			(at 0 0 90)
			(layer "F.SilkS")
			(hide yes)
			(effects
				(font
					(size 1.27 1.27)
				)
			)
		)
		(property "Value" ""
			(at 0 0 90)
			(layer "F.Fab")
			(effects
				(font
					(size 1.27 1.27)
				)
			)
		)
		(duplicate_pad_numbers_are_jumpers no)
		(fp_rect
			(start -0.2794 -0.1016)
			(end 0.2794 0.9906)
			(stroke
				(width 0)
				(type default)
			)
			(fill no)
			(layer "F.CrtYd")
		)
		(fp_line
			(start 0.2794 -0.1016)
			(end -0.2794 -0.1016)
			(stroke
				(width 0.1)
				(type default)
			)
			(layer "F.Fab")
		)
		(fp_line
			(start -0.2794 -0.1016)
			(end -0.2794 0.9906)
			(stroke
				(width 0.1)
				(type default)
			)
			(layer "F.Fab")
		)
		(fp_line
			(start 0.2794 0.9906)
			(end 0.2794 -0.1016)
			(stroke
				(width 0.1)
				(type default)
			)
			(layer "F.Fab")
		)
		(fp_line
			(start -0.2794 0.9906)
			(end 0.2794 0.9906)
			(stroke
				(width 0.1)
				(type default)
			)
			(layer "F.Fab")
		)
		(pad "1" smd rect
			(at 0 0 90)
			(size 0.508 0.508)
			(layers "F.Cu" "F.Mask" "F.Paste")
			(net "PVCCIO_CPU0")
		)
		(pad "2" smd rect
			(at 0 0.889 90)
			(size 0.508 0.508)
			(layers "F.Cu" "F.Mask" "F.Paste")
			(net "H_CPU0_MSMI_G_N")
		)
		(zone
			(layer "F.Cu")
			(hatch none 0.5)
			(connect_pads
				(clearance 0)
			)
			(min_thickness 0.25)
			(keepout
				(tracks allowed)
				(vias not_allowed)
				(pads allowed)
				(copperpour not_allowed)
				(footprints allowed)
			)
			(placement
				(enabled no)
				(sheetname "")
			)
			(fill
				(thermal_gap 0.5)
				(thermal_bridge_width 0.5)
				(island_removal_mode 0)
			)
			(polygon
				(pts
					(xy 281.432 -72.898) (xy 281.813 -72.898) (xy 281.813 -73.406) (xy 281.432 -73.406)
				)
			)
		)
		(zone
			(layer "F.Cu")
			(hatch none 0.5)
			(connect_pads
				(clearance 0)
			)
			(min_thickness 0.25)
			(keepout
				(tracks not_allowed)
				(vias allowed)
				(pads allowed)
				(copperpour not_allowed)
				(footprints allowed)
			)
			(placement
				(enabled no)
				(sheetname "")
			)
			(fill
				(thermal_gap 0.5)
				(thermal_bridge_width 0.5)
				(island_removal_mode 0)
			)
			(polygon
				(pts
					(xy 281.432 -72.898) (xy 281.813 -72.898) (xy 281.813 -73.406) (xy 281.432 -73.406)
				)
			)
		)
	)
	(footprint ""
		(layer "F.Cu")
		(at 4.295394 -12.815824 90)
		(property "Reference" "C1G14"
			(at 0 0 90)
			(layer "F.SilkS")
			(hide yes)
			(effects
				(font
					(size 1.27 1.27)
				)
			)
		)
		(property "Value" ""
			(at 0 0 90)
			(layer "F.Fab")
			(effects
				(font
					(size 1.27 1.27)
				)
			)
		)
		(duplicate_pad_numbers_are_jumpers no)
		(fp_rect
			(start 0.3048 -0.1016)
			(end -0.3048 0.9906)
			(stroke
				(width 0)
				(type default)
			)
			(fill no)
			(layer "F.CrtYd")
		)
		(fp_line
			(start 0.3048 -0.1016)
			(end -0.3048 -0.1016)
			(stroke
				(width 0.1)
				(type default)
			)
			(layer "F.Fab")
		)
		(fp_line
			(start -0.3048 -0.1016)
			(end -0.3048 0.9906)
			(stroke
				(width 0.1)
				(type default)
			)
			(layer "F.Fab")
		)
		(fp_line
			(start 0.3048 0.9906)
			(end 0.3048 -0.1016)
			(stroke
				(width 0.1)
				(type default)
			)
			(layer "F.Fab")
		)
		(fp_line
			(start -0.3048 0.9906)
			(end 0.3048 0.9906)
			(stroke
				(width 0.1)
				(type default)
			)
			(layer "F.Fab")
		)
		(pad "1" smd rect
			(at 0 0 90)
			(size 0.508 0.508)
			(layers "F.Cu" "F.Mask" "F.Paste")
			(net "VR_FET_SW_P12V_STBY_PVDDQ_GHJ")
		)
		(pad "2" smd rect
			(at 0 0.889 90)
			(size 0.508 0.508)
			(layers "F.Cu" "F.Mask" "F.Paste")
			(net "GND")
		)
		(zone
			(layer "F.Cu")
			(hatch none 0.5)
			(connect_pads
				(clearance 0)
			)
			(min_thickness 0.25)
			(keepout
				(tracks not_allowed)
				(vias allowed)
				(pads allowed)
				(copperpour not_allowed)
				(footprints allowed)
			)
			(placement
				(enabled no)
				(sheetname "")
			)
			(fill
				(thermal_gap 0.5)
				(thermal_bridge_width 0.5)
				(island_removal_mode 0)
			)
			(polygon
				(pts
					(xy 4.549394 -13.069824) (xy 4.549394 -12.561824) (xy 4.930394 -12.561824) (xy 4.930394 -13.069824)
				)
			)
		)
		(zone
			(layer "F.Cu")
			(hatch none 0.5)
			(connect_pads
				(clearance 0)
			)
			(min_thickness 0.25)
			(keepout
				(tracks allowed)
				(vias not_allowed)
				(pads allowed)
				(copperpour not_allowed)
				(footprints allowed)
			)
			(placement
				(enabled no)
				(sheetname "")
			)
			(fill
				(thermal_gap 0.5)
				(thermal_bridge_width 0.5)
				(island_removal_mode 0)
			)
			(polygon
				(pts
					(xy 4.549394 -13.069824) (xy 4.549394 -12.561824) (xy 4.930394 -12.561824) (xy 4.930394 -13.069824)
				)
			)
		)
	)
)
